# usb-c-power-adapter — KiCad project settings (.kicad_pro: net classes, design rules, text variables)
{
  "board": {
    "3dviewports": [],
    "design_settings": {
      "defaults": {
        "apply_defaults_to_fp_fields": false,
        "apply_defaults_to_fp_shapes": false,
        "apply_defaults_to_fp_text": false,
        "board_outline_line_width": 0.05,
        "copper_line_width": 0.2,
        "copper_text_italic": false,
        "copper_text_size_h": 1.5,
        "copper_text_size_v": 1.5,
        "copper_text_thickness": 0.3,
        "copper_text_upright": false,
        "courtyard_line_width": 0.05,
        "dimension_precision": 4,
        "dimension_units": 3,
        "dimensions": {
          "arrow_length": 1270000,
          "extension_offset": 500000,
          "keep_text_aligned": true,
          "suppress_zeroes": false,
          "text_position": 0,
          "units_format": 1
        },
        "fab_line_width": 0.1,
        "fab_text_italic": false,
        "fab_text_size_h": 1.0,
        "fab_text_size_v": 1.0,
        "fab_text_thickness": 0.15,
        "fab_text_upright": false,
        "other_line_width": 0.1,
        "other_text_italic": false,
        "other_text_size_h": 1.0,
        "other_text_size_v": 1.0,
        "other_text_thickness": 0.15,
        "other_text_upright": false,
        "pads": {
          "drill": 0.0,
          "height": 0.6,
          "width": 0.3
        },
        "silk_line_width": 0.1,
        "silk_text_italic": false,
        "silk_text_size_h": 1.0,
        "silk_text_size_v": 1.0,
        "silk_text_thickness": 0.1,
        "silk_text_upright": false,
        "zones": {
          "min_clearance": 0.25
        }
      },
      "diff_pair_dimensions": [
        {
          "gap": 0.0,
          "via_gap": 0.0,
          "width": 0.0
        }
      ],
      "drc_exclusions": [],
      "meta": {
        "version": 2
      },
      "rule_severities": {
        "annular_width": "error",
        "clearance": "error",
        "connection_width": "warning",
        "copper_edge_clearance": "error",
        "copper_sliver": "warning",
        "courtyards_overlap": "error",
        "creepage": "error",
        "diff_pair_gap_out_of_range": "error",
        "diff_pair_uncoupled_length_too_long": "error",
        "drill_out_of_range": "error",
        "duplicate_footprints": "warning",
        "extra_footprint": "warning",
        "footprint": "error",
        "footprint_filters_mismatch": "ignore",
        "footprint_symbol_mismatch": "warning",
        "footprint_type_mismatch": "ignore",
        "hole_clearance": "error",
        "hole_near_hole": "error",
        "hole_to_hole": "error",
        "holes_co_located": "error",
        "invalid_outline": "error",
        "isolated_copper": "warning",
        "item_on_disabled_layer": "error",
        "items_not_allowed": "error",
        "length_out_of_range": "error",
        "lib_footprint_issues": "warning",
        "lib_footprint_mismatch": "warning",
        "malformed_courtyard": "error",
        "microvia_drill_out_of_range": "error",
        "mirrored_text_on_front_layer": "warning",
        "missing_courtyard": "warning",
        "missing_footprint": "warning",
        "net_conflict": "warning",
        "nonmirrored_text_on_back_layer": "warning",
        "npth_inside_courtyard": "warning",
        "padstack": "error",
        "pth_inside_courtyard": "warning",
        "shorting_items": "error",
        "silk_edge_clearance": "warning",
        "silk_over_copper": "warning",
        "silk_overlap": "warning",
        "skew_out_of_range": "error",
        "solder_mask_bridge": "error",
        "starved_thermal": "error",
        "text_height": "warning",
        "text_on_edge_cuts": "error",
        "text_thickness": "warning",
        "through_hole_pad_without_hole": "error",
        "too_many_vias": "error",
        "track_angle": "error",
        "track_dangling": "warning",
        "track_segment_length": "error",
        "track_width": "error",
        "tracks_crossing": "error",
        "unconnected_items": "error",
        "unresolved_variable": "error",
        "via_dangling": "warning",
        "zones_intersect": "error"
      },
      "rules": {
        "max_error": 0.005,
        "min_clearance": 0.125,
        "min_connection": 0.0,
        "min_copper_edge_clearance": 0.4,
        "min_groove_width": 0.0,
        "min_hole_clearance": 0.2,
        "min_hole_to_hole": 0.25,
        "min_microvia_diameter": 0.2,
        "min_microvia_drill": 0.1,
        "min_resolved_spokes": 1,
        "min_silk_clearance": 0.0,
        "min_text_height": 0.7,
        "min_text_thickness": 0.08,
        "min_through_hole_diameter": 0.2,
        "min_track_width": 0.125,
        "min_via_annular_width": 0.125,
        "min_via_diameter": 0.45,
        "solder_mask_to_copper_clearance": 0.0,
        "use_height_for_length_calcs": true
      },
      "teardrop_options": [
        {
          "td_onpthpad": true,
          "td_onroundshapesonly": false,
          "td_onsmdpad": true,
          "td_ontrackend": false,
          "td_onvia": true
        }
      ],
      "teardrop_parameters": [
        {
          "td_allow_use_two_tracks": true,
          "td_curve_segcount": 0,
          "td_height_ratio": 1.0,
          "td_length_ratio": 0.5,
          "td_maxheight": 2.0,
          "td_maxlen": 1.0,
          "td_on_pad_in_zone": false,
          "td_target_name": "td_round_shape",
          "td_width_to_size_filter_ratio": 0.9
        },
        {
          "td_allow_use_two_tracks": true,
          "td_curve_segcount": 0,
          "td_height_ratio": 1.0,
          "td_length_ratio": 0.5,
          "td_maxheight": 2.0,
          "td_maxlen": 1.0,
          "td_on_pad_in_zone": false,
          "td_target_name": "td_rect_shape",
          "td_width_to_size_filter_ratio": 0.9
        },
        {
          "td_allow_use_two_tracks": true,
          "td_curve_segcount": 0,
          "td_height_ratio": 1.0,
          "td_length_ratio": 0.5,
          "td_maxheight": 2.0,
          "td_maxlen": 1.0,
          "td_on_pad_in_zone": false,
          "td_target_name": "td_track_end",
          "td_width_to_size_filter_ratio": 0.9
        }
      ],
      "track_widths": [
        0.0,
        0.15,
        0.2,
        0.25,
        0.3,
        0.4,
        0.5,
        1.0,
        1.5
      ],
      "tuning_pattern_settings": {
        "diff_pair_defaults": {
          "corner_radius_percentage": 80,
          "corner_style": 1,
          "max_amplitude": 1.0,
          "min_amplitude": 0.2,
          "single_sided": false,
          "spacing": 1.0
        },
        "diff_pair_skew_defaults": {
          "corner_radius_percentage": 80,
          "corner_style": 1,
          "max_amplitude": 1.0,
          "min_amplitude": 0.2,
          "single_sided": false,
          "spacing": 0.6
        },
        "single_track_defaults": {
          "corner_radius_percentage": 80,
          "corner_style": 1,
          "max_amplitude": 1.0,
          "min_amplitude": 0.2,
          "single_sided": false,
          "spacing": 0.6
        }
      },
      "via_dimensions": [
        {
          "diameter": 0.0,
          "drill": 0.0
        },
        {
          "diameter": 0.55,
          "drill": 0.25
        },
        {
          "diameter": 0.6,
          "drill": 0.3
        }
      ],
      "zones_allow_external_fillets": false
    },
    "ipc2581": {
      "dist": "",
      "distpn": "",
      "internal_id": "",
      "mfg": "",
      "mpn": ""
    },
    "layer_pairs": [],
    "layer_presets": [],
    "viewports": []
  },
  "boards": [],
  "cvpcb": {
    "equivalence_files": []
  },
  "erc": {
    "erc_exclusions": [],
    "meta": {
      "version": 0
    },
    "pin_map": [
      [
        0,
        0,
        0,
        0,
        0,
        0,
        1,
        0,
        0,
        0,
        0,
        2
      ],
      [
        0,
        2,
        0,
        1,
        0,
        0,
        1,
        0,
        2,
        2,
        2,
        2
      ],
      [
        0,
        0,
        0,
        0,
        0,
        0,
        1,
        0,
        1,
        0,
        1,
        2
      ],
      [
        0,
        1,
        0,
        0,
        0,
        0,
        1,
        1,
        2,
        1,
        1,
        2
      ],
      [
        0,
        0,
        0,
        0,
        0,
        0,
        1,
        0,
        0,
        0,
        0,
        2
      ],
      [
        0,
        0,
        0,
        0,
        0,
        0,
        0,
        0,
        0,
        0,
        0,
        2
      ],
      [
        1,
        1,
        1,
        1,
        1,
        0,
        1,
        1,
        1,
        1,
        1,
        2
      ],
      [
        0,
        0,
        0,
        1,
        0,
        0,
        1,
        0,
        0,
        0,
        0,
        2
      ],
      [
        0,
        2,
        1,
        2,
        0,
        0,
        1,
        0,
        2,
        2,
        2,
        2
      ],
      [
        0,
        2,
        0,
        1,
        0,
        0,
        1,
        0,
        2,
        0,
        0,
        2
      ],
      [
        0,
        2,
        1,
        1,
        0,
        0,
        1,
        0,
        2,
        0,
        0,
        2
      ],
      [
        2,
        2,
        2,
        2,
        2,
        2,
        2,
        2,
        2,
        2,
        2,
        2
      ]
    ],
    "rule_severities": {
      "bus_definition_conflict": "error",
      "bus_entry_needed": "error",
      "bus_to_bus_conflict": "error",
      "bus_to_net_conflict": "error",
      "conflicting_netclasses": "error",
      "different_unit_footprint": "error",
      "different_unit_net": "error",
      "duplicate_reference": "error",
      "duplicate_sheet_names": "error",
      "endpoint_off_grid": "warning",
      "extra_units": "error",
      "footprint_filter": "warning",
      "footprint_link_issues": "ignore",
      "four_way_junction": "ignore",
      "global_label_dangling": "warning",
      "hier_label_mismatch": "error",
      "label_dangling": "error",
      "label_multiple_wires": "warning",
      "lib_symbol_issues": "warning",
      "lib_symbol_mismatch": "warning",
      "missing_bidi_pin": "warning",
      "missing_input_pin": "warning",
      "missing_power_pin": "error",
      "missing_unit": "warning",
      "multiple_net_names": "warning",
      "net_not_bus_member": "warning",
      "no_connect_connected": "error",
      "no_connect_dangling": "warning",
      "pin_not_connected": "error",
      "pin_not_driven": "error",
      "pin_to_pin": "ignore",
      "power_pin_not_driven": "error",
      "same_local_global_label": "warning",
      "similar_label_and_power": "warning",
      "similar_labels": "warning",
      "similar_power": "warning",
      "simulation_model_issue": "ignore",
      "single_global_label": "warning",
      "unannotated": "error",
      "unconnected_wire_endpoint": "warning",
      "unit_value_mismatch": "error",
      "unresolved_variable": "error",
      "wire_dangling": "error"
    }
  },
  "libraries": {
    "pinned_footprint_libs": [],
    "pinned_symbol_libs": []
  },
  "meta": {
    "filename": "usb-c-power-adapter.kicad_pro",
    "version": 3
  },
  "net_settings": {
    "classes": [
      {
        "bus_width": 12,
        "clearance": 0.125,
        "diff_pair_gap": 0.25,
        "diff_pair_via_gap": 0.25,
        "diff_pair_width": 0.2,
        "line_style": 0,
        "microvia_diameter": 0.3,
        "microvia_drill": 0.1,
        "name": "Default",
        "pcb_color": "rgba(0, 0, 0, 0.000)",
        "priority": 2147483647,
        "schematic_color": "rgba(0, 0, 0, 0.000)",
        "track_width": 0.125,
        "via_diameter": 0.45,
        "via_drill": 0.2,
        "wire_width": 6
      },
      {
        "bus_width": 12,
        "clearance": 0.125,
        "diff_pair_gap": 0.25,
        "diff_pair_via_gap": 0.25,
        "diff_pair_width": 0.2,
        "line_style": 0,
        "microvia_diameter": 0.3,
        "microvia_drill": 0.1,
        "name": "USB",
        "pcb_color": "rgba(0, 0, 0, 0.000)",
        "priority": 0,
        "schematic_color": "rgba(0, 0, 0, 0.000)",
        "track_width": 0.125,
        "via_diameter": 0.6,
        "via_drill": 0.3,
        "wire_width": 6
      }
    ],
    "meta": {
      "version": 4
    },
    "net_colors": null,
    "netclass_assignments": null,
    "netclass_patterns": [
      {
        "netclass": "USB",
        "pattern": "/USB.*"
      }
    ]
  },
  "pcbnew": {
    "last_paths": {
      "gencad": "",
      "idf": "",
      "netlist": "",
      "plot": "",
      "pos_files": "",
      "specctra_dsn": "",
      "step": "",
      "svg": "",
      "vrml": ""
    },
    "page_layout_descr_file": ""
  },
  "schematic": {
    "annotate_start_num": 0,
    "bom_export_filename": "",
    "bom_fmt_presets": [],
    "bom_fmt_settings": {
      "field_delimiter": ",",
      "keep_line_breaks": false,
      "keep_tabs": false,
      "name": "CSV",
      "ref_delimiter": ",",
      "ref_range_delimiter": "",
      "string_delimiter": "\""
    },
    "bom_presets": [],
    "bom_settings": {
      "exclude_dnp": false,
      "fields_ordered": [
        {
          "group_by": false,
          "label": "Reference",
          "name": "Reference",
          "show": true
        },
        {
          "group_by": true,
          "label": "Value",
          "name": "Value",
          "show": true
        },
        {
          "group_by": false,
          "label": "Datasheet",
          "name": "Datasheet",
          "show": true
        },
        {
          "group_by": false,
          "label": "Footprint",
          "name": "Footprint",
          "show": true
        },
        {
          "group_by": false,
          "label": "Qty",
          "name": "${QUANTITY}",
          "show": true
        },
        {
          "group_by": true,
          "label": "DNP",
          "name": "${DNP}",
          "show": true
        }
      ],
      "filter_string": "",
      "group_symbols": true,
      "include_excluded_from_bom": false,
      "name": "Grouped By Value",
      "sort_asc": true,
      "sort_field": "Reference"
    },
    "connection_grid_size": 50.0,
    "drawing": {
      "dashed_lines_dash_length_ratio": 12.0,
      "dashed_lines_gap_length_ratio": 3.0,
      "default_line_thickness": 6.0,
      "default_text_size": 50.0,
      "field_names": [],
      "intersheets_ref_own_page": false,
      "intersheets_ref_prefix": "",
      "intersheets_ref_short": false,
      "intersheets_ref_show": false,
      "intersheets_ref_suffix": "",
      "junction_size_choice": 3,
      "label_size_ratio": 0.375,
      "operating_point_overlay_i_precision": 3,
      "operating_point_overlay_i_range": "~A",
      "operating_point_overlay_v_precision": 3,
      "operating_point_overlay_v_range": "~V",
      "overbar_offset_ratio": 1.23,
      "pin_symbol_size": 25.0,
      "text_offset_ratio": 0.15
    },
    "legacy_lib_dir": "",
    "legacy_lib_list": [],
    "meta": {
      "version": 1
    },
    "net_format_name": "",
    "page_layout_descr_file": "",
    "plot_directory": "",
    "space_save_all_events": true,
    "spice_current_sheet_as_root": false,
    "spice_external_command": "spice \"%I\"",
    "spice_model_current_sheet_as_root": true,
    "spice_save_all_currents": false,
    "spice_save_all_dissipations": false,
    "spice_save_all_voltages": false,
    "subpart_first_id": 65,
    "subpart_id_separator": 0
  },
  "sheets": [
    [
      "",
      "Root"
    ],
    [
      "",
      "USB PD"
    ],
    [
      "",
      "DC-DC Converters"
    ]
  ],
  "text_variables": {}
}
